(kicad_pcb
	(version 20241229)
	(generator "pcbnew")
	(generator_version "9.0")
	(general
		(thickness 1.62)
		(legacy_teardrops no)
	)
	(paper "A3")
	(title_block
		(title "COM Express 7 Baseboard")
		(date "2025-02-04")
		(rev "1.1.2")
		(company "Antmicro Ltd")
		(comment 1 "www.antmicro.com")
		(comment 9 "footprints 490-493 of 802")
	)
	(layers
		(0 "F.Cu" signal)
		(4 "In1.Cu" signal)
		(6 "In2.Cu" signal)
		(8 "In3.Cu" signal)
		(10 "In4.Cu" signal)
		(12 "In5.Cu" signal)
		(14 "In6.Cu" signal)
		(2 "B.Cu" signal)
		(9 "F.Adhes" user "F.Adhesive")
		(11 "B.Adhes" user "B.Adhesive")
		(13 "F.Paste" user)
		(15 "B.Paste" user)
		(5 "F.SilkS" user "F.Silkscreen")
		(7 "B.SilkS" user "B.Silkscreen")
		(1 "F.Mask" user)
		(3 "B.Mask" user)
		(17 "Dwgs.User" user "User.Drawings")
		(19 "Cmts.User" user "User.Comments")
		(21 "Eco1.User" user "User.Eco1")
		(23 "Eco2.User" user "User.Eco2")
		(25 "Edge.Cuts" user)
		(27 "Margin" user)
		(31 "F.CrtYd" user "F.Courtyard")
		(29 "B.CrtYd" user "B.Courtyard")
		(35 "F.Fab" user)
		(33 "B.Fab" user)
	)
	(footprint "antmicro-footprints:USON-10_2.5x1mm_P0.5mm"
		(layer "F.Cu")
		(at 112.15 137.91)
		(descr "USON-10 2.5x1mm_ Pitch 0.5mm")
		(tags "USON-10 2.5x1mm Pitch 0.5mm")
		(property "Reference" "U46"
			(at 1.75 1.15 90)
			(layer "F.SilkS")
			(effects
				(font
					(size 0.7 0.7)
					(thickness 0.15)
				)
				(justify left bottom)
			)
		)
		(property "Value" "ESD204DQAR"
			(at 0.018 2.499 0)
			(layer "F.Fab")
			(effects
				(font
					(size 0.7 0.7)
					(thickness 0.15)
				)
				(justify left bottom)
			)
		)
		(property "Datasheet" "https://www.ti.com/lit/ds/symlink/esd204.pdf?ts=1706004844383&ref_url=https%253A%252F%252Fwww.ti.com%252Finterface%252Fdiodes%252Fesd-protection-diodes%252Fproducts.html"
			(at 0 0 0)
			(layer "F.Fab")
			(hide yes)
			(effects
				(font
					(size 1.27 1.27)
					(thickness 0.15)
				)
			)
		)
		(property "Author" "Antmicro"
			(at 0 0 0)
			(layer "F.Fab")
			(hide yes)
			(effects
				(font
					(size 1 1)
					(thickness 0.15)
				)
			)
		)
		(property "License" "Apache-2.0"
			(at 0 0 0)
			(layer "F.Fab")
			(hide yes)
			(effects
				(font
					(size 1 1)
					(thickness 0.15)
				)
			)
		)
		(property "MPN" "ESD204DQAR"
			(at 0 0 0)
			(layer "F.Fab")
			(hide yes)
			(effects
				(font
					(size 1 1)
					(thickness 0.15)
				)
			)
		)
		(property "Manufacturer" "Texas Instruments"
			(at 0 0 0)
			(layer "F.Fab")
			(hide yes)
			(effects
				(font
					(size 1 1)
					(thickness 0.15)
				)
			)
		)
		(sheetname "SD card")
		(sheetfile "sd_card.kicad_sch")
		(attr smd)
		(fp_line
			(start 0.498 -1.401)
			(end -0.5 -1.401)
			(stroke
				(width 0.15)
				(type solid)
			)
			(layer "F.SilkS")
		)
		(fp_line
			(start 0.498 1.398)
			(end -0.5 1.398)
			(stroke
				(width 0.15)
				(type solid)
			)
			(layer "F.SilkS")
		)
		(fp_circle
			(center -0.68 -1.27)
			(end -0.63 -1.27)
			(stroke
				(width 0.15)
				(type solid)
			)
			(fill yes)
			(layer "F.SilkS")
		)
		(fp_rect
			(start -0.8 -1.5)
			(end 0.8 1.499)
			(stroke
				(width 0.05)
				(type solid)
			)
			(fill no)
			(layer "F.CrtYd")
		)
		(fp_line
			(start -0.5 -1)
			(end -0.5 1.249)
			(stroke
				(width 0.15)
				(type solid)
			)
			(layer "F.Fab")
		)
		(fp_line
			(start -0.5 1.249)
			(end 0.498 1.249)
			(stroke
				(width 0.15)
				(type solid)
			)
			(layer "F.Fab")
		)
		(fp_line
			(start -0.25 -1.25)
			(end -0.5 -1)
			(stroke
				(width 0.15)
				(type solid)
			)
			(layer "F.Fab")
		)
		(fp_line
			(start 0.498 -1.25)
			(end -0.25 -1.25)
			(stroke
				(width 0.15)
				(type solid)
			)
			(layer "F.Fab")
		)
		(fp_line
			(start 0.498 -1.25)
			(end 0.498 1.249)
			(stroke
				(width 0.15)
				(type solid)
			)
			(layer "F.Fab")
		)
		(pad "1" smd roundrect
			(at -0.387 -1 270)
			(size 0.25 0.55)
			(layers "F.Cu" "F.Mask" "F.Paste")
			(roundrect_rratio 0.25)
			(net 385 "/Com Express 7 Interfaces/SDIO.CMD")
			(pintype "passive")
			(teardrops
				(best_length_ratio 0.2)
				(max_length 1)
				(best_width_ratio 0.9)
				(max_width 2)
				(curved_edges yes)
				(filter_ratio 0.9)
				(enabled yes)
				(allow_two_segments yes)
				(prefer_zone_connections yes)
			)
		)
		(pad "2" smd roundrect
			(at -0.387 -0.5 270)
			(size 0.25 0.55)
			(layers "F.Cu" "F.Mask" "F.Paste")
			(roundrect_rratio 0.25)
			(net 333 "/Com Express 7 Interfaces/SDIO.DAT3")
			(pintype "passive")
			(teardrops
				(best_length_ratio 0.2)
				(max_length 1)
				(best_width_ratio 0.9)
				(max_width 2)
				(curved_edges yes)
				(filter_ratio 0.9)
				(enabled yes)
				(allow_two_segments yes)
				(prefer_zone_connections yes)
			)
		)
		(pad "3" smd roundrect
			(at -0.387 0 270)
			(size 0.4 0.55)
			(layers "F.Cu" "F.Mask" "F.Paste")
			(roundrect_rratio 0.25)
			(net 1 "GND")
			(pintype "power_in")
			(teardrops
				(best_length_ratio 0.2)
				(max_length 1)
				(best_width_ratio 0.9)
				(max_width 2)
				(curved_edges yes)
				(filter_ratio 0.9)
				(enabled yes)
				(allow_two_segments yes)
				(prefer_zone_connections yes)
			)
		)
		(pad "4" smd roundrect
			(at -0.387 0.498 270)
			(size 0.25 0.55)
			(layers "F.Cu" "F.Mask" "F.Paste")
			(roundrect_rratio 0.25)
			(net 323 "/Com Express 7 Interfaces/SDIO.DAT2")
			(pintype "passive")
			(teardrops
				(best_length_ratio 0.2)
				(max_length 1)
				(best_width_ratio 0.9)
				(max_width 2)
				(curved_edges yes)
				(filter_ratio 0.9)
				(enabled yes)
				(allow_two_segments yes)
				(prefer_zone_connections yes)
			)
		)
		(pad "5" smd roundrect
			(at -0.387 0.998 270)
			(size 0.25 0.55)
			(layers "F.Cu" "F.Mask" "F.Paste")
			(roundrect_rratio 0.25)
			(net 890 "unconnected-(U46-Pad5)")
			(pintype "passive+no_connect")
			(teardrops
				(best_length_ratio 0.2)
				(max_length 1)
				(best_width_ratio 0.9)
				(max_width 2)
				(curved_edges yes)
				(filter_ratio 0.9)
				(enabled yes)
				(allow_two_segments yes)
				(prefer_zone_connections yes)
			)
		)
		(pad "6" smd roundrect
			(at 0.385 0.998 270)
			(size 0.25 0.55)
			(layers "F.Cu" "F.Mask" "F.Paste")
			(roundrect_rratio 0.25)
			(net 998 "unconnected-(U46-Pad5)_1")
			(pintype "passive+no_connect")
			(teardrops
				(best_length_ratio 0.2)
				(max_length 1)
				(best_width_ratio 0.9)
				(max_width 2)
				(curved_edges yes)
				(filter_ratio 0.9)
				(enabled yes)
				(allow_two_segments yes)
				(prefer_zone_connections yes)
			)
		)
		(pad "7" smd roundrect
			(at 0.385 0.498 270)
			(size 0.25 0.55)
			(layers "F.Cu" "F.Mask" "F.Paste")
			(roundrect_rratio 0.25)
			(net 323 "/Com Express 7 Interfaces/SDIO.DAT2")
			(pintype "passive")
			(teardrops
				(best_length_ratio 0.2)
				(max_length 1)
				(best_width_ratio 0.9)
				(max_width 2)
				(curved_edges yes)
				(filter_ratio 0.9)
				(enabled yes)
				(allow_two_segments yes)
				(prefer_zone_connections yes)
			)
		)
		(pad "8" smd roundrect
			(at 0.385 0 270)
			(size 0.4 0.55)
			(layers "F.Cu" "F.Mask" "F.Paste")
			(roundrect_rratio 0.25)
			(net 1 "GND")
			(pintype "passive")
			(teardrops
				(best_length_ratio 0.2)
				(max_length 1)
				(best_width_ratio 0.9)
				(max_width 2)
				(curved_edges yes)
				(filter_ratio 0.9)
				(enabled yes)
				(allow_two_segments yes)
				(prefer_zone_connections yes)
			)
		)
		(pad "9" smd roundrect
			(at 0.385 -0.5 270)
			(size 0.25 0.55)
			(layers "F.Cu" "F.Mask" "F.Paste")
			(roundrect_rratio 0.25)
			(net 333 "/Com Express 7 Interfaces/SDIO.DAT3")
			(pintype "passive")
			(teardrops
				(best_length_ratio 0.2)
				(max_length 1)
				(best_width_ratio 0.9)
				(max_width 2)
				(curved_edges yes)
				(filter_ratio 0.9)
				(enabled yes)
				(allow_two_segments yes)
				(prefer_zone_connections yes)
			)
		)
		(pad "10" smd roundrect
			(at 0.385 -1 270)
			(size 0.25 0.55)
			(layers "F.Cu" "F.Mask" "F.Paste")
			(roundrect_rratio 0.25)
			(net 385 "/Com Express 7 Interfaces/SDIO.CMD")
			(pintype "passive")
			(teardrops
				(best_length_ratio 0.2)
				(max_length 1)
				(best_width_ratio 0.9)
				(max_width 2)
				(curved_edges yes)
				(filter_ratio 0.9)
				(enabled yes)
				(allow_two_segments yes)
				(prefer_zone_connections yes)
			)
		)
	)
	(footprint "antmicro-footprints:R_0402_1005Metric"
		(layer "F.Cu")
		(at 312.075499 136.46 90)
		(descr "Resistor SMD 0402")
		(tags "resistor SMD 0402")
		(property "Reference" "R106"
			(at 0.2 5.674501 90)
			(layer "F.SilkS")
			(effects
				(font
					(size 0.7 0.7)
					(thickness 0.15)
				)
				(justify left bottom)
			)
		)
		(property "Value" "R_0R_0402"
			(at -1.011843 1.772047 90)
			(layer "F.Fab")
			(effects
				(font
					(size 0.7 0.7)
					(thickness 0.15)
				)
				(justify left bottom)
			)
		)
		(property "Datasheet" "https://industrial.panasonic.com/cdbs/www-data/pdf/RDA0000/AOA0000C301.pdf"
			(at 0 0 90)
			(layer "F.Fab")
			(hide yes)
			(effects
				(font
					(size 1.27 1.27)
					(thickness 0.15)
				)
			)
		)
		(property "Author" "Antmicro"
			(at 448.535499 -175.615499 0)
			(layer "F.Fab")
			(hide yes)
			(effects
				(font
					(size 1 1)
					(thickness 0.15)
				)
			)
		)
		(property "Current" "1A"
			(at 448.535499 -175.615499 0)
			(layer "F.Fab")
			(hide yes)
			(effects
				(font
					(size 1 1)
					(thickness 0.15)
				)
			)
		)
		(property "License" "Apache-2.0"
			(at 448.535499 -175.615499 0)
			(layer "F.Fab")
			(hide yes)
			(effects
				(font
					(size 1 1)
					(thickness 0.15)
				)
			)
		)
		(property "MPN" "ERJ2GE0R00X"
			(at 448.535499 -175.615499 0)
			(layer "F.Fab")
			(hide yes)
			(effects
				(font
					(size 1 1)
					(thickness 0.15)
				)
			)
		)
		(property "Manufacturer" "Panasonic"
			(at 448.535499 -175.615499 0)
			(layer "F.Fab")
			(hide yes)
			(effects
				(font
					(size 1 1)
					(thickness 0.15)
				)
			)
		)
		(property "Public" "False"
			(at 448.535499 -175.615499 0)
			(layer "F.Fab")
			(hide yes)
			(effects
				(font
					(size 1 1)
					(thickness 0.15)
				)
			)
		)
		(property "Tolerance" ""
			(at 448.535499 -175.615499 0)
			(layer "F.Fab")
			(hide yes)
			(effects
				(font
					(size 1 1)
					(thickness 0.15)
				)
			)
		)
		(property "Val" "0R"
			(at 448.535499 -175.615499 0)
			(layer "F.Fab")
			(hide yes)
			(effects
				(font
					(size 1 1)
					(thickness 0.15)
				)
			)
		)
		(sheetname "Power")
		(sheetfile "power.kicad_sch")
		(attr smd)
		(fp_rect
			(start -0.925 -0.47)
			(end 0.925 0.47)
			(stroke
				(width 0.05)
				(type default)
			)
			(fill no)
			(layer "F.CrtYd")
		)
		(fp_rect
			(start -0.5 -0.25)
			(end 0.5 0.25)
			(stroke
				(width 0.15)
				(type solid)
			)
			(fill no)
			(layer "F.Fab")
		)
		(pad "1" smd roundrect
			(at -0.48 0 90)
			(size 0.59 0.64)
			(layers "F.Cu" "F.Mask" "F.Paste")
			(roundrect_rratio 0.25)
			(net 889 "/Power/PG_{3V3}")
			(pintype "passive")
			(teardrops
				(best_length_ratio 0.2)
				(max_length 1)
				(best_width_ratio 0.9)
				(max_width 2)
				(curved_edges yes)
				(filter_ratio 0.9)
				(enabled yes)
				(allow_two_segments yes)
				(prefer_zone_connections yes)
			)
		)
		(pad "2" smd roundrect
			(at 0.48 0 90)
			(size 0.59 0.64)
			(layers "F.Cu" "F.Mask" "F.Paste")
			(roundrect_rratio 0.25)
			(net 583 "Net-(U22-EN)")
			(pintype "passive")
			(teardrops
				(best_length_ratio 0.2)
				(max_length 1)
				(best_width_ratio 0.9)
				(max_width 2)
				(curved_edges yes)
				(filter_ratio 0.9)
				(enabled yes)
				(allow_two_segments yes)
				(prefer_zone_connections yes)
			)
		)
	)
	(footprint "antmicro-footprints:C_0402_1005Metric"
		(layer "F.Cu")
		(at 262.430708 75.76)
		(descr "Capacitor SMD 0402")
		(tags "capacitor SMD 0402")
		(property "Reference" "C90"
			(at -3.01 0.45 0)
			(layer "F.SilkS")
			(effects
				(font
					(size 0.7 0.7)
					(thickness 0.15)
				)
				(justify left bottom)
			)
		)
		(property "Value" "C_100n_0402"
			(at -1.022927 2.155213 0)
			(layer "F.Fab")
			(effects
				(font
					(size 0.7 0.7)
					(thickness 0.15)
				)
				(justify left bottom)
			)
		)
		(property "Datasheet" "https://www.murata.com/products/productdetail?partno=GRM155R61H104KE14%23"
			(at 0 0 0)
			(layer "F.Fab")
			(hide yes)
			(effects
				(font
					(size 1.27 1.27)
					(thickness 0.15)
				)
			)
		)
		(property "Author" "Antmicro"
			(at 0 0 0)
			(layer "F.Fab")
			(hide yes)
			(effects
				(font
					(size 1 1)
					(thickness 0.15)
				)
			)
		)
		(property "Dielectric" "X5R"
			(at 0 0 0)
			(layer "F.Fab")
			(hide yes)
			(effects
				(font
					(size 1 1)
					(thickness 0.15)
				)
			)
		)
		(property "License" "Apache-2.0"
			(at 0 0 0)
			(layer "F.Fab")
			(hide yes)
			(effects
				(font
					(size 1 1)
					(thickness 0.15)
				)
			)
		)
		(property "MPN" "GRM155R61H104KE14D"
			(at 0 0 0)
			(layer "F.Fab")
			(hide yes)
			(effects
				(font
					(size 1 1)
					(thickness 0.15)
				)
			)
		)
		(property "Manufacturer" "Murata"
			(at 0 0 0)
			(layer "F.Fab")
			(hide yes)
			(effects
				(font
					(size 1 1)
					(thickness 0.15)
				)
			)
		)
		(property "Public" "False"
			(at 0 0 0)
			(layer "F.Fab")
			(hide yes)
			(effects
				(font
					(size 1 1)
					(thickness 0.15)
				)
			)
		)
		(property "Val" "100n"
			(at 0 0 0)
			(layer "F.Fab")
			(hide yes)
			(effects
				(font
					(size 1 1)
					(thickness 0.15)
				)
			)
		)
		(property "Voltage" "50V"
			(at 0 0 0)
			(layer "F.Fab")
			(hide yes)
			(effects
				(font
					(size 1 1)
					(thickness 0.15)
				)
			)
		)
		(sheetname "Misc")
		(sheetfile "misc.kicad_sch")
		(attr smd)
		(fp_rect
			(start -0.925 -0.47)
			(end 0.925 0.47)
			(stroke
				(width 0.05)
				(type default)
			)
			(fill no)
			(layer "F.CrtYd")
		)
		(fp_line
			(start -0.494 -0.25)
			(end 0.504 -0.25)
			(stroke
				(width 0.15)
				(type solid)
			)
			(layer "F.Fab")
		)
		(fp_line
			(start -0.494 0.248)
			(end -0.494 -0.25)
			(stroke
				(width 0.15)
				(type solid)
			)
			(layer "F.Fab")
		)
		(fp_line
			(start 0.504 -0.25)
			(end 0.504 0.248)
			(stroke
				(width 0.15)
				(type solid)
			)
			(layer "F.Fab")
		)
		(fp_line
			(start 0.504 0.248)
			(end -0.494 0.248)
			(stroke
				(width 0.15)
				(type solid)
			)
			(layer "F.Fab")
		)
		(pad "1" smd roundrect
			(at -0.48 0)
			(size 0.59 0.64)
			(layers "F.Cu" "F.Mask" "F.Paste")
			(roundrect_rratio 0.25)
			(net 1 "GND")
			(pintype "passive")
			(teardrops
				(best_length_ratio 0.2)
				(max_length 1)
				(best_width_ratio 0.9)
				(max_width 2)
				(curved_edges yes)
				(filter_ratio 0.9)
				(enabled yes)
				(allow_two_segments yes)
				(prefer_zone_connections yes)
			)
		)
		(pad "2" smd roundrect
			(at 0.48 0)
			(size 0.59 0.64)
			(layers "F.Cu" "F.Mask" "F.Paste")
			(roundrect_rratio 0.25)
			(net 52 "+5V")
			(pintype "passive")
			(teardrops
				(best_length_ratio 0.2)
				(max_length 1)
				(best_width_ratio 0.9)
				(max_width 2)
				(curved_edges yes)
				(filter_ratio 0.9)
				(enabled yes)
				(allow_two_segments yes)
				(prefer_zone_connections yes)
			)
		)
	)
	(footprint "antmicro-footprints:C_0402_1005Metric"
		(layer "F.Cu")
		(at 191.780956 136.25552 135)
		(descr "Capacitor SMD 0402")
		(tags "capacitor SMD 0402")
		(property "Reference" "C122"
			(at 3.844168 0.29978 135)
			(layer "F.SilkS")
			(effects
				(font
					(size 0.7 0.7)
					(thickness 0.15)
				)
				(justify left top)
			)
		)
		(property "Value" "C_100n_0402"
			(at -1.022927 2.155213 135)
			(layer "F.Fab")
			(effects
				(font
					(size 0.7 0.7)
					(thickness 0.15)
				)
				(justify left top)
			)
		)
		(property "Datasheet" "https://www.murata.com/products/productdetail?partno=GRM155R61H104KE14%23"
			(at 0 0 135)
			(layer "B.Fab")
			(hide yes)
			(effects
				(font
					(size 1.27 1.27)
					(thickness 0.15)
				)
				(justify mirror)
			)
		)
		(property "Author" "Antmicro"
			(at 325.014 56.288 45)
			(layer "F.Fab")
			(hide yes)
			(effects
				(font
					(size 1 1)
					(thickness 0.15)
				)
			)
		)
		(property "Dielectric" "X5R"
			(at 325.014 56.288 45)
			(layer "F.Fab")
			(hide yes)
			(effects
				(font
					(size 1 1)
					(thickness 0.15)
				)
			)
		)
		(property "License" "Apache-2.0"
			(at 325.014 56.288 45)
			(layer "F.Fab")
			(hide yes)
			(effects
				(font
					(size 1 1)
					(thickness 0.15)
				)
			)
		)
		(property "MPN" "GRM155R61H104KE14D"
			(at 325.014 56.288 45)
			(layer "F.Fab")
			(hide yes)
			(effects
				(font
					(size 1 1)
					(thickness 0.15)
				)
			)
		)
		(property "Manufacturer" "Murata"
			(at 325.014 56.288 45)
			(layer "F.Fab")
			(hide yes)
			(effects
				(font
					(size 1 1)
					(thickness 0.15)
				)
			)
		)
		(property "Public" "False"
			(at 325.014 56.288 45)
			(layer "F.Fab")
			(hide yes)
			(effects
				(font
					(size 1 1)
					(thickness 0.15)
				)
			)
		)
		(property "Val" "100n"
			(at 325.014 56.288 45)
			(layer "F.Fab")
			(hide yes)
			(effects
				(font
					(size 1 1)
					(thickness 0.15)
				)
			)
		)
		(property "Voltage" "50V"
			(at 325.014 56.288 45)
			(layer "F.Fab")
			(hide yes)
			(effects
				(font
					(size 1 1)
					(thickness 0.15)
				)
			)
		)
		(sheetname "PCIe redriver")
		(sheetfile "pcie_redriver.kicad_sch")
		(attr smd)
		(fp_poly
			(pts
				(xy -0.925 -0.47) (xy 0.925 -0.47) (xy 0.925 0.47) (xy -0.925 0.47)
			)
			(stroke
				(width 0.05)
				(type default)
			)
			(fill no)
			(layer "F.CrtYd")
		)
		(fp_line
			(start 0.504 -0.25)
			(end 0.504 0.248)
			(stroke
				(width 0.15)
				(type solid)
			)
			(layer "F.Fab")
		)
		(fp_line
			(start 0.504 0.248)
			(end -0.494 0.248)
			(stroke
				(width 0.15)
				(type solid)
			)
			(layer "F.Fab")
		)
		(fp_line
			(start -0.494 -0.25)
			(end 0.504 -0.25)
			(stroke
				(width 0.15)
				(type solid)
			)
			(layer "F.Fab")
		)
		(fp_line
			(start -0.494 0.248)
			(end -0.494 -0.25)
			(stroke
				(width 0.15)
				(type solid)
			)
			(layer "F.Fab")
		)
		(pad "1" smd roundrect
			(at -0.48 0 135)
			(size 0.59 0.64)
			(layers "F.Cu" "F.Mask" "F.Paste")
			(roundrect_rratio 0.25)
			(net 1 "GND")
			(pintype "passive")
			(teardrops
				(best_length_ratio 0.2)
				(max_length 1)
				(best_width_ratio 0.9)
				(max_width 2)
				(curved_edges yes)
				(filter_ratio 0.9)
				(enabled yes)
				(allow_two_segments yes)
				(prefer_zone_connections yes)
			)
		)
		(pad "2" smd roundrect
			(at 0.48 0 135)
			(size 0.59 0.64)
			(layers "F.Cu" "F.Mask" "F.Paste")
			(roundrect_rratio 0.25)
			(net 2 "+3V3")
			(pintype "passive")
			(teardrops
				(best_length_ratio 0.2)
				(max_length 1)
				(best_width_ratio 0.9)
				(max_width 2)
				(curved_edges yes)
				(filter_ratio 0.9)
				(enabled yes)
				(allow_two_segments yes)
				(prefer_zone_connections yes)
			)
		)
	)
)
